(kicad_pcb
	(version 20260206)
	(generator "pcbnew")
	(generator_version "10.0")
	(general
		(thickness 1.6)
		(legacy_teardrops no)
	)
	(paper "A4")
	(title_block
		(title "Wiwynn_Tioga_Pass_MB.brd")
		(comment 1 "Tioga Pass / footprints 1474-1481 of 4770")
	)
	(layers
		(0 "F.Cu" signal "TOP")
		(4 "In1.Cu" signal "L2GND")
		(6 "In2.Cu" signal "L3")
		(8 "In3.Cu" signal "L4GND")
		(10 "In4.Cu" signal "L5")
		(12 "In5.Cu" signal "L6GND")
		(14 "In6.Cu" signal "L7VCC")
		(16 "In7.Cu" signal "L8VCC")
		(18 "In8.Cu" signal "L9GND")
		(20 "In9.Cu" signal "L10")
		(22 "In10.Cu" signal "L11GND")
		(24 "In11.Cu" signal "L12")
		(26 "In12.Cu" signal "L13GND")
		(2 "B.Cu" signal "BOTTOM")
		(9 "F.Adhes" user "F.Adhesive")
		(11 "B.Adhes" user "B.Adhesive")
		(13 "F.Paste" user "Package Geometry/Pastemask Top")
		(15 "B.Paste" user "Package Geometry/Pastemask Bottom")
		(5 "F.SilkS" user "Ref Des/Silkscreen Top")
		(7 "B.SilkS" user "Ref Des/Silkscreen Bottom")
		(1 "F.Mask" user "Board Geometry/Soldermask Top")
		(3 "B.Mask" user "Board Geometry/Soldermask Bottom")
		(17 "Dwgs.User" user "User.Drawings")
		(19 "Cmts.User" user "User.Comments")
		(21 "Eco1.User" user "User.Eco1")
		(23 "Eco2.User" user "User.Eco2")
		(25 "Edge.Cuts" user "Board Geometry/Outline")
		(27 "Margin" user)
		(31 "F.CrtYd" user "Package Geometry/Place Bound Top")
		(29 "B.CrtYd" user "Package Geometry/Place Bound Bottom")
		(35 "F.Fab" user "Ref Des/Assembly Top")
		(33 "B.Fab" user "Ref Des/Assembly Bottom")
	)
	(footprint ""
		(layer "F.Cu")
		(at 475.2594 -148.9456 180)
		(property "Reference" "R9A9"
			(at 0 0 180)
			(layer "F.SilkS")
			(hide yes)
			(effects
				(font
					(size 1.27 1.27)
				)
			)
		)
		(property "Value" ""
			(at 0 0 180)
			(layer "F.Fab")
			(effects
				(font
					(size 1.27 1.27)
				)
			)
		)
		(duplicate_pad_numbers_are_jumpers no)
		(fp_poly
			(pts
				(xy -0.2794 -0.1016) (xy 0.2794 -0.1016) (xy 0.2794 0.9906) (xy -0.2794 0.9906)
			)
			(stroke
				(width 0)
				(type default)
			)
			(fill no)
			(layer "F.CrtYd")
		)
		(fp_line
			(start 0.2794 0.9906)
			(end 0.2794 -0.1016)
			(stroke
				(width 0.1)
				(type default)
			)
			(layer "F.Fab")
		)
		(fp_line
			(start 0.2794 -0.1016)
			(end -0.2794 -0.1016)
			(stroke
				(width 0.1)
				(type default)
			)
			(layer "F.Fab")
		)
		(fp_line
			(start -0.2794 0.9906)
			(end 0.2794 0.9906)
			(stroke
				(width 0.1)
				(type default)
			)
			(layer "F.Fab")
		)
		(fp_line
			(start -0.2794 -0.1016)
			(end -0.2794 0.9906)
			(stroke
				(width 0.1)
				(type default)
			)
			(layer "F.Fab")
		)
		(pad "1" smd rect
			(at 0 0 180)
			(size 0.508 0.508)
			(layers "F.Cu" "F.Mask" "F.Paste")
			(net "RST_SYSTEM_BTN_BUF_N")
		)
		(pad "2" smd rect
			(at 0 0.889 180)
			(size 0.508 0.508)
			(layers "F.Cu" "F.Mask" "F.Paste")
			(net "RST_SYSTEM_BTN_N")
		)
		(zone
			(layer "F.Cu")
			(hatch none 0.5)
			(connect_pads
				(clearance 0)
			)
			(min_thickness 0.25)
			(keepout
				(tracks not_allowed)
				(vias allowed)
				(pads allowed)
				(copperpour not_allowed)
				(footprints allowed)
			)
			(placement
				(enabled no)
				(sheetname "")
			)
			(fill
				(thermal_gap 0.5)
				(thermal_bridge_width 0.5)
				(island_removal_mode 0)
			)
			(polygon
				(pts
					(xy 475.5134 -149.5806) (xy 475.0054 -149.5806) (xy 475.0054 -149.1996) (xy 475.5134 -149.1996)
				)
			)
		)
		(zone
			(layer "F.Cu")
			(hatch none 0.5)
			(connect_pads
				(clearance 0)
			)
			(min_thickness 0.25)
			(keepout
				(tracks allowed)
				(vias not_allowed)
				(pads allowed)
				(copperpour not_allowed)
				(footprints allowed)
			)
			(placement
				(enabled no)
				(sheetname "")
			)
			(fill
				(thermal_gap 0.5)
				(thermal_bridge_width 0.5)
				(island_removal_mode 0)
			)
			(polygon
				(pts
					(xy 475.5134 -149.1996) (xy 475.0054 -149.1996) (xy 475.0054 -149.5806) (xy 475.5134 -149.5806)
				)
			)
		)
	)
	(footprint ""
		(layer "F.Cu")
		(at 410.997146 -22.996652 90)
		(property "Reference" "C25W9"
			(at -0.8382 -0.67818 90)
			(unlocked yes)
			(layer "F.SilkS")
			(effects
				(font
					(size 0.4064 0.254)
					(thickness 0.1524)
				)
				(justify left)
			)
		)
		(property "Value" ""
			(at 0 0 90)
			(layer "F.Fab")
			(effects
				(font
					(size 1.27 1.27)
				)
			)
		)
		(duplicate_pad_numbers_are_jumpers no)
		(fp_poly
			(pts
				(xy 0.3048 -0.1016) (xy 0.3048 0.9906) (xy -0.3048 0.9906) (xy -0.3048 -0.1016)
			)
			(stroke
				(width 0)
				(type default)
			)
			(fill no)
			(layer "F.CrtYd")
		)
		(fp_line
			(start 0.3048 -0.1016)
			(end -0.3048 -0.1016)
			(stroke
				(width 0.1)
				(type default)
			)
			(layer "F.Fab")
		)
		(fp_line
			(start -0.3048 -0.1016)
			(end -0.3048 0.9906)
			(stroke
				(width 0.1)
				(type default)
			)
			(layer "F.Fab")
		)
		(fp_line
			(start 0.3048 0.9906)
			(end 0.3048 -0.1016)
			(stroke
				(width 0.1)
				(type default)
			)
			(layer "F.Fab")
		)
		(fp_line
			(start -0.3048 0.9906)
			(end 0.3048 0.9906)
			(stroke
				(width 0.1)
				(type default)
			)
			(layer "F.Fab")
		)
		(pad "1" smd rect
			(at 0 0 90)
			(size 0.508 0.508)
			(layers "F.Cu" "F.Mask" "F.Paste")
			(net "P3V3_STBY_BMC_ADCVREFP")
		)
		(pad "2" smd rect
			(at 0 0.889 90)
			(size 0.508 0.508)
			(layers "F.Cu" "F.Mask" "F.Paste")
			(net "P3V3_STBY_BMC_ADCVREFN")
		)
		(zone
			(layer "F.Cu")
			(hatch none 0.5)
			(connect_pads
				(clearance 0)
			)
			(min_thickness 0.25)
			(keepout
				(tracks allowed)
				(vias not_allowed)
				(pads allowed)
				(copperpour not_allowed)
				(footprints allowed)
			)
			(placement
				(enabled no)
				(sheetname "")
			)
			(fill
				(thermal_gap 0.5)
				(thermal_bridge_width 0.5)
				(island_removal_mode 0)
			)
			(polygon
				(pts
					(xy 411.251146 -22.742652) (xy 411.251146 -23.250652) (xy 411.632146 -23.250652) (xy 411.632146 -22.742652)
				)
			)
		)
		(zone
			(layer "F.Cu")
			(hatch none 0.5)
			(connect_pads
				(clearance 0)
			)
			(min_thickness 0.25)
			(keepout
				(tracks not_allowed)
				(vias allowed)
				(pads allowed)
				(copperpour not_allowed)
				(footprints allowed)
			)
			(placement
				(enabled no)
				(sheetname "")
			)
			(fill
				(thermal_gap 0.5)
				(thermal_bridge_width 0.5)
				(island_removal_mode 0)
			)
			(polygon
				(pts
					(xy 411.632146 -22.742652) (xy 411.632146 -23.250652) (xy 411.251146 -23.250652) (xy 411.251146 -22.742652)
				)
			)
		)
	)
	(footprint ""
		(layer "F.Cu")
		(at 385.2164 -50.8508 90)
		(property "Reference" "R8F8"
			(at 0 0 90)
			(layer "F.SilkS")
			(hide yes)
			(effects
				(font
					(size 1.27 1.27)
				)
			)
		)
		(property "Value" ""
			(at 0 0 90)
			(layer "F.Fab")
			(effects
				(font
					(size 1.27 1.27)
				)
			)
		)
		(duplicate_pad_numbers_are_jumpers no)
		(fp_poly
			(pts
				(xy -0.2794 -0.1016) (xy 0.2794 -0.1016) (xy 0.2794 0.9906) (xy -0.2794 0.9906)
			)
			(stroke
				(width 0)
				(type default)
			)
			(fill no)
			(layer "F.CrtYd")
		)
		(fp_line
			(start 0.2794 -0.1016)
			(end -0.2794 -0.1016)
			(stroke
				(width 0.1)
				(type default)
			)
			(layer "F.Fab")
		)
		(fp_line
			(start -0.2794 -0.1016)
			(end -0.2794 0.9906)
			(stroke
				(width 0.1)
				(type default)
			)
			(layer "F.Fab")
		)
		(fp_line
			(start 0.2794 0.9906)
			(end 0.2794 -0.1016)
			(stroke
				(width 0.1)
				(type default)
			)
			(layer "F.Fab")
		)
		(fp_line
			(start -0.2794 0.9906)
			(end 0.2794 0.9906)
			(stroke
				(width 0.1)
				(type default)
			)
			(layer "F.Fab")
		)
		(pad "1" smd rect
			(at 0 0 90)
			(size 0.508 0.508)
			(layers "F.Cu" "F.Mask" "F.Paste")
			(net "SPI_SWITCH_CLK")
		)
		(pad "2" smd rect
			(at 0 0.889 90)
			(size 0.508 0.508)
			(layers "F.Cu" "F.Mask" "F.Paste")
			(net "SPI_CLK_R0")
		)
		(zone
			(layer "F.Cu")
			(hatch none 0.5)
			(connect_pads
				(clearance 0)
			)
			(min_thickness 0.25)
			(keepout
				(tracks allowed)
				(vias not_allowed)
				(pads allowed)
				(copperpour not_allowed)
				(footprints allowed)
			)
			(placement
				(enabled no)
				(sheetname "")
			)
			(fill
				(thermal_gap 0.5)
				(thermal_bridge_width 0.5)
				(island_removal_mode 0)
			)
			(polygon
				(pts
					(xy 385.4704 -50.5968) (xy 385.4704 -51.1048) (xy 385.8514 -51.1048) (xy 385.8514 -50.5968)
				)
			)
		)
		(zone
			(layer "F.Cu")
			(hatch none 0.5)
			(connect_pads
				(clearance 0)
			)
			(min_thickness 0.25)
			(keepout
				(tracks not_allowed)
				(vias allowed)
				(pads allowed)
				(copperpour not_allowed)
				(footprints allowed)
			)
			(placement
				(enabled no)
				(sheetname "")
			)
			(fill
				(thermal_gap 0.5)
				(thermal_bridge_width 0.5)
				(island_removal_mode 0)
			)
			(polygon
				(pts
					(xy 385.8514 -50.5968) (xy 385.8514 -51.1048) (xy 385.4704 -51.1048) (xy 385.4704 -50.5968)
				)
			)
		)
	)
	(footprint ""
		(layer "F.Cu")
		(at 318.543432 -140.208 -90)
		(property "Reference" "C6A6"
			(at 0 0 270)
			(layer "F.SilkS")
			(hide yes)
			(effects
				(font
					(size 1.27 1.27)
				)
			)
		)
		(property "Value" ""
			(at 0 0 270)
			(layer "F.Fab")
			(effects
				(font
					(size 1.27 1.27)
				)
			)
		)
		(duplicate_pad_numbers_are_jumpers no)
		(fp_poly
			(pts
				(xy -0.4953 -0.2032) (xy 0.4953 -0.2032) (xy 0.4953 1.6002) (xy -0.4953 1.6002)
			)
			(stroke
				(width 0)
				(type default)
			)
			(fill no)
			(layer "F.CrtYd")
		)
		(fp_line
			(start -0.4953 1.6002)
			(end -0.4953 -0.2032)
			(stroke
				(width 0.1)
				(type default)
			)
			(layer "F.Fab")
		)
		(fp_line
			(start 0.4953 1.6002)
			(end -0.4953 1.6002)
			(stroke
				(width 0.1)
				(type default)
			)
			(layer "F.Fab")
		)
		(fp_line
			(start -0.4953 -0.2032)
			(end 0.4953 -0.2032)
			(stroke
				(width 0.1)
				(type default)
			)
			(layer "F.Fab")
		)
		(fp_line
			(start 0.4953 -0.2032)
			(end 0.4953 1.6002)
			(stroke
				(width 0.1)
				(type default)
			)
			(layer "F.Fab")
		)
		(pad "1" smd rect
			(at 0 0 270)
			(size 0.762 0.889)
			(layers "F.Cu" "F.Mask" "F.Paste")
			(net "PVPP_DEF")
		)
		(pad "2" smd rect
			(at 0 1.397 270)
			(size 0.762 0.889)
			(layers "F.Cu" "F.Mask" "F.Paste")
			(net "GND")
		)
		(zone
			(layer "F.Cu")
			(hatch none 0.5)
			(connect_pads
				(clearance 0)
			)
			(min_thickness 0.25)
			(keepout
				(tracks not_allowed)
				(vias allowed)
				(pads allowed)
				(copperpour not_allowed)
				(footprints allowed)
			)
			(placement
				(enabled no)
				(sheetname "")
			)
			(fill
				(thermal_gap 0.5)
				(thermal_bridge_width 0.5)
				(island_removal_mode 0)
			)
			(polygon
				(pts
					(xy 318.098932 -140.589) (xy 318.098932 -139.827) (xy 317.590932 -139.827) (xy 317.590932 -140.589)
				)
			)
		)
	)
	(footprint ""
		(layer "F.Cu")
		(at 369.7224 -130.429 180)
		(property "Reference" "C7B22"
			(at 0 0 180)
			(layer "F.SilkS")
			(hide yes)
			(effects
				(font
					(size 1.27 1.27)
				)
			)
		)
		(property "Value" ""
			(at 0 0 180)
			(layer "F.Fab")
			(effects
				(font
					(size 1.27 1.27)
				)
			)
		)
		(duplicate_pad_numbers_are_jumpers no)
		(fp_poly
			(pts
				(xy -0.4953 -0.2032) (xy 0.4953 -0.2032) (xy 0.4953 1.6002) (xy -0.4953 1.6002)
			)
			(stroke
				(width 0)
				(type default)
			)
			(fill no)
			(layer "F.CrtYd")
		)
		(fp_line
			(start 0.4953 1.6002)
			(end -0.4953 1.6002)
			(stroke
				(width 0.1)
				(type default)
			)
			(layer "F.Fab")
		)
		(fp_line
			(start 0.4953 -0.2032)
			(end 0.4953 1.6002)
			(stroke
				(width 0.1)
				(type default)
			)
			(layer "F.Fab")
		)
		(fp_line
			(start -0.4953 1.6002)
			(end -0.4953 -0.2032)
			(stroke
				(width 0.1)
				(type default)
			)
			(layer "F.Fab")
		)
		(fp_line
			(start -0.4953 -0.2032)
			(end 0.4953 -0.2032)
			(stroke
				(width 0.1)
				(type default)
			)
			(layer "F.Fab")
		)
		(pad "1" smd rect
			(at 0 0 180)
			(size 0.762 0.889)
			(layers "F.Cu" "F.Mask" "F.Paste")
			(net "P1V05_PCH_STBY")
		)
		(pad "2" smd rect
			(at 0 1.397 180)
			(size 0.762 0.889)
			(layers "F.Cu" "F.Mask" "F.Paste")
			(net "GND")
		)
		(zone
			(layer "F.Cu")
			(hatch none 0.5)
			(connect_pads
				(clearance 0)
			)
			(min_thickness 0.25)
			(keepout
				(tracks not_allowed)
				(vias allowed)
				(pads allowed)
				(copperpour not_allowed)
				(footprints allowed)
			)
			(placement
				(enabled no)
				(sheetname "")
			)
			(fill
				(thermal_gap 0.5)
				(thermal_bridge_width 0.5)
				(island_removal_mode 0)
			)
			(polygon
				(pts
					(xy 370.1034 -130.8735) (xy 369.3414 -130.8735) (xy 369.3414 -131.3815) (xy 370.1034 -131.3815)
				)
			)
		)
	)
	(footprint ""
		(layer "F.Cu")
		(at 352.153982 -95.497904 -90)
		(property "Reference" "C7C14"
			(at 0 0 270)
			(layer "F.SilkS")
			(hide yes)
			(effects
				(font
					(size 1.27 1.27)
				)
			)
		)
		(property "Value" ""
			(at 0 0 270)
			(layer "F.Fab")
			(effects
				(font
					(size 1.27 1.27)
				)
			)
		)
		(duplicate_pad_numbers_are_jumpers no)
		(fp_poly
			(pts
				(xy 0.3048 -0.1016) (xy 0.3048 0.9906) (xy -0.3048 0.9906) (xy -0.3048 -0.1016)
			)
			(stroke
				(width 0)
				(type default)
			)
			(fill no)
			(layer "F.CrtYd")
		)
		(fp_line
			(start -0.3048 0.9906)
			(end 0.3048 0.9906)
			(stroke
				(width 0.1)
				(type default)
			)
			(layer "F.Fab")
		)
		(fp_line
			(start 0.3048 0.9906)
			(end 0.3048 -0.1016)
			(stroke
				(width 0.1)
				(type default)
			)
			(layer "F.Fab")
		)
		(fp_line
			(start -0.3048 -0.1016)
			(end -0.3048 0.9906)
			(stroke
				(width 0.1)
				(type default)
			)
			(layer "F.Fab")
		)
		(fp_line
			(start 0.3048 -0.1016)
			(end -0.3048 -0.1016)
			(stroke
				(width 0.1)
				(type default)
			)
			(layer "F.Fab")
		)
		(pad "1" smd rect
			(at 0 0 270)
			(size 0.508 0.508)
			(layers "F.Cu" "F.Mask" "F.Paste")
			(net "VR_PVCCIO_CPU0_PH1_BOOT")
		)
		(pad "2" smd rect
			(at 0 0.889 270)
			(size 0.508 0.508)
			(layers "F.Cu" "F.Mask" "F.Paste")
			(net "VR_PVCCIO_CPU0_PH1_PHASE")
		)
		(zone
			(layer "F.Cu")
			(hatch none 0.5)
			(connect_pads
				(clearance 0)
			)
			(min_thickness 0.25)
			(keepout
				(tracks not_allowed)
				(vias allowed)
				(pads allowed)
				(copperpour not_allowed)
				(footprints allowed)
			)
			(placement
				(enabled no)
				(sheetname "")
			)
			(fill
				(thermal_gap 0.5)
				(thermal_bridge_width 0.5)
				(island_removal_mode 0)
			)
			(polygon
				(pts
					(xy 351.518982 -95.751904) (xy 351.518982 -95.243904) (xy 351.899982 -95.243904) (xy 351.899982 -95.751904)
				)
			)
		)
		(zone
			(layer "F.Cu")
			(hatch none 0.5)
			(connect_pads
				(clearance 0)
			)
			(min_thickness 0.25)
			(keepout
				(tracks allowed)
				(vias not_allowed)
				(pads allowed)
				(copperpour not_allowed)
				(footprints allowed)
			)
			(placement
				(enabled no)
				(sheetname "")
			)
			(fill
				(thermal_gap 0.5)
				(thermal_bridge_width 0.5)
				(island_removal_mode 0)
			)
			(polygon
				(pts
					(xy 351.899982 -95.751904) (xy 351.899982 -95.243904) (xy 351.518982 -95.243904) (xy 351.518982 -95.751904)
				)
			)
		)
	)
	(footprint ""
		(layer "F.Cu")
		(at 194.564 -2.8575 180)
		(property "Reference" "R4G22"
			(at 0 0 180)
			(layer "F.SilkS")
			(hide yes)
			(effects
				(font
					(size 1.27 1.27)
				)
			)
		)
		(property "Value" ""
			(at 0 0 180)
			(layer "F.Fab")
			(effects
				(font
					(size 1.27 1.27)
				)
			)
		)
		(duplicate_pad_numbers_are_jumpers no)
		(fp_poly
			(pts
				(xy -0.2794 -0.1016) (xy 0.2794 -0.1016) (xy 0.2794 0.9906) (xy -0.2794 0.9906)
			)
			(stroke
				(width 0)
				(type default)
			)
			(fill no)
			(layer "F.CrtYd")
		)
		(fp_line
			(start 0.2794 0.9906)
			(end 0.2794 -0.1016)
			(stroke
				(width 0.1)
				(type default)
			)
			(layer "F.Fab")
		)
		(fp_line
			(start 0.2794 -0.1016)
			(end -0.2794 -0.1016)
			(stroke
				(width 0.1)
				(type default)
			)
			(layer "F.Fab")
		)
		(fp_line
			(start -0.2794 0.9906)
			(end 0.2794 0.9906)
			(stroke
				(width 0.1)
				(type default)
			)
			(layer "F.Fab")
		)
		(fp_line
			(start -0.2794 -0.1016)
			(end -0.2794 0.9906)
			(stroke
				(width 0.1)
				(type default)
			)
			(layer "F.Fab")
		)
		(pad "1" smd rect
			(at 0 0 180)
			(size 0.508 0.508)
			(layers "F.Cu" "F.Mask" "F.Paste")
			(net "M_C_VREF")
		)
		(pad "2" smd rect
			(at 0 0.889 180)
			(size 0.508 0.508)
			(layers "F.Cu" "F.Mask" "F.Paste")
			(net "GND")
		)
		(zone
			(layer "F.Cu")
			(hatch none 0.5)
			(connect_pads
				(clearance 0)
			)
			(min_thickness 0.25)
			(keepout
				(tracks not_allowed)
				(vias allowed)
				(pads allowed)
				(copperpour not_allowed)
				(footprints allowed)
			)
			(placement
				(enabled no)
				(sheetname "")
			)
			(fill
				(thermal_gap 0.5)
				(thermal_bridge_width 0.5)
				(island_removal_mode 0)
			)
			(polygon
				(pts
					(xy 194.818 -3.4925) (xy 194.31 -3.4925) (xy 194.31 -3.1115) (xy 194.818 -3.1115)
				)
			)
		)
		(zone
			(layer "F.Cu")
			(hatch none 0.5)
			(connect_pads
				(clearance 0)
			)
			(min_thickness 0.25)
			(keepout
				(tracks allowed)
				(vias not_allowed)
				(pads allowed)
				(copperpour not_allowed)
				(footprints allowed)
			)
			(placement
				(enabled no)
				(sheetname "")
			)
			(fill
				(thermal_gap 0.5)
				(thermal_bridge_width 0.5)
				(island_removal_mode 0)
			)
			(polygon
				(pts
					(xy 194.818 -3.1115) (xy 194.31 -3.1115) (xy 194.31 -3.4925) (xy 194.818 -3.4925)
				)
			)
		)
	)
	(footprint ""
		(layer "F.Cu")
		(at 382.002284 -56.32958 90)
		(property "Reference" "R7F37"
			(at 0 0 90)
			(layer "F.SilkS")
			(hide yes)
			(effects
				(font
					(size 1.27 1.27)
				)
			)
		)
		(property "Value" ""
			(at 0 0 90)
			(layer "F.Fab")
			(effects
				(font
					(size 1.27 1.27)
				)
			)
		)
		(duplicate_pad_numbers_are_jumpers no)
		(fp_poly
			(pts
				(xy -0.2794 -0.1016) (xy 0.2794 -0.1016) (xy 0.2794 0.9906) (xy -0.2794 0.9906)
			)
			(stroke
				(width 0)
				(type default)
			)
			(fill no)
			(layer "F.CrtYd")
		)
		(fp_line
			(start 0.2794 -0.1016)
			(end -0.2794 -0.1016)
			(stroke
				(width 0.1)
				(type default)
			)
			(layer "F.Fab")
		)
		(fp_line
			(start -0.2794 -0.1016)
			(end -0.2794 0.9906)
			(stroke
				(width 0.1)
				(type default)
			)
			(layer "F.Fab")
		)
		(fp_line
			(start 0.2794 0.9906)
			(end 0.2794 -0.1016)
			(stroke
				(width 0.1)
				(type default)
			)
			(layer "F.Fab")
		)
		(fp_line
			(start -0.2794 0.9906)
			(end 0.2794 0.9906)
			(stroke
				(width 0.1)
				(type default)
			)
			(layer "F.Fab")
		)
		(pad "1" smd rect
			(at 0 0 90)
			(size 0.508 0.508)
			(layers "F.Cu" "F.Mask" "F.Paste")
			(net "SPI_BIOS_SOCKET_IO2")
		)
		(pad "2" smd rect
			(at 0 0.889 90)
			(size 0.508 0.508)
			(layers "F.Cu" "F.Mask" "F.Paste")
			(net "PU_BIOS_SPI_WP0_N")
		)
		(zone
			(layer "F.Cu")
			(hatch none 0.5)
			(connect_pads
				(clearance 0)
			)
			(min_thickness 0.25)
			(keepout
				(tracks allowed)
				(vias not_allowed)
				(pads allowed)
				(copperpour not_allowed)
				(footprints allowed)
			)
			(placement
				(enabled no)
				(sheetname "")
			)
			(fill
				(thermal_gap 0.5)
				(thermal_bridge_width 0.5)
				(island_removal_mode 0)
			)
			(polygon
				(pts
					(xy 382.256284 -56.07558) (xy 382.256284 -56.58358) (xy 382.637284 -56.58358) (xy 382.637284 -56.07558)
				)
			)
		)
		(zone
			(layer "F.Cu")
			(hatch none 0.5)
			(connect_pads
				(clearance 0)
			)
			(min_thickness 0.25)
			(keepout
				(tracks not_allowed)
				(vias allowed)
				(pads allowed)
				(copperpour not_allowed)
				(footprints allowed)
			)
			(placement
				(enabled no)
				(sheetname "")
			)
			(fill
				(thermal_gap 0.5)
				(thermal_bridge_width 0.5)
				(island_removal_mode 0)
			)
			(polygon
				(pts
					(xy 382.637284 -56.07558) (xy 382.637284 -56.58358) (xy 382.256284 -56.58358) (xy 382.256284 -56.07558)
				)
			)
		)
	)
)
